G04*
G04 #@! TF.GenerationSoftware,Altium Limited,Altium Designer,23.7.1 (13)*
G04*
G04 Layer_Color=16711935*
%FSLAX25Y25*%
%MOIN*%
G70*
G04*
G04 #@! TF.SameCoordinates,AF00DCEB-AC48-4C7C-91EA-99F42E284231*
G04*
G04*
G04 #@! TF.FilePolarity,Negative*
G04*
G01*
G75*
%ADD52R,0.01457X0.00945*%
%ADD53R,0.01575X0.04252*%
%ADD86R,0.02816X0.02648*%
%ADD87R,0.02016X0.02288*%
%ADD88R,0.02911X0.02648*%
%ADD89R,0.02756X0.02756*%
%ADD113R,0.02648X0.02911*%
%ADD120R,0.02288X0.02016*%
%ADD124R,0.02648X0.02816*%
%ADD149R,0.31496X0.13583*%
%ADD150R,1.35433X0.23032*%
%ADD155R,0.02572X0.02572*%
%ADD156R,0.05131X0.04934*%
%ADD157R,0.04934X0.05131*%
%ADD166R,0.02769X0.02572*%
%ADD168R,0.02965X0.02965*%
%ADD172R,0.02572X0.02769*%
%ADD173R,0.02965X0.02965*%
%ADD177R,0.03359X0.03162*%
%ADD188R,0.03162X0.03359*%
%ADD202R,0.03600X0.17300*%
%ADD203R,0.03600X0.13400*%
%ADD206C,0.06902*%
%ADD207R,0.06902X0.06902*%
%ADD208C,0.07099*%
%ADD209R,0.07099X0.07099*%
%ADD210C,0.11800*%
%ADD211R,0.10827X0.10827*%
%ADD212C,0.10827*%
%ADD213C,0.25800*%
%ADD214O,0.05721X0.04934*%
%ADD215O,0.08280X0.05524*%
%ADD216C,0.00800*%
%ADD217C,0.06299*%
%ADD218C,0.04331*%
%ADD219C,0.26391*%
%ADD220C,0.02966*%
%ADD221C,0.10800*%
%ADD222C,0.24800*%
%ADD223R,0.00800X0.00800*%
%ADD224C,0.09461*%
%ADD225R,0.08674X0.08674*%
%ADD226R,0.06706X0.06706*%
%ADD227C,0.06706*%
%ADD228C,0.02400*%
%ADD229C,0.20800*%
%ADD259R,0.01968X0.02362*%
%ADD260R,0.02712X0.02648*%
%ADD262R,0.02362X0.01968*%
%ADD266R,0.03937X0.04921*%
%ADD267R,0.04921X0.03937*%
%ADD268R,0.02029X0.01860*%
%ADD271R,0.02756X0.02756*%
G04:AMPARAMS|DCode=276|XSize=33.98mil|YSize=20.6mil|CornerRadius=5.58mil|HoleSize=0mil|Usage=FLASHONLY|Rotation=0.000|XOffset=0mil|YOffset=0mil|HoleType=Round|Shape=RoundedRectangle|*
%AMROUNDEDRECTD276*
21,1,0.03398,0.00945,0,0,0.0*
21,1,0.02284,0.02060,0,0,0.0*
1,1,0.01115,0.01142,-0.00472*
1,1,0.01115,-0.01142,-0.00472*
1,1,0.01115,-0.01142,0.00472*
1,1,0.01115,0.01142,0.00472*
%
%ADD276ROUNDEDRECTD276*%
%ADD277R,0.03359X0.03359*%
%ADD278R,0.03359X0.03359*%
%ADD279R,0.03359X0.03556*%
%ADD280R,0.03635X0.04737*%
%ADD281R,0.02965X0.02769*%
%ADD282R,0.03753X0.03556*%
%ADD283R,0.02572X0.02572*%
%ADD284R,0.04147X0.03753*%
%ADD285R,0.03950X0.04540*%
%ADD286R,0.03005X0.02847*%
%ADD287R,0.03320X0.03477*%
%ADD288R,0.03477X0.03320*%
%ADD289R,0.03162X0.03950*%
D52*
X587625Y-281567D02*
D03*
Y-279992D02*
D03*
Y-278418D02*
D03*
X591680D02*
D03*
Y-279992D02*
D03*
Y-281567D02*
D03*
D53*
X589652Y-279992D02*
D03*
D86*
X97553Y-77165D02*
D03*
X93785D02*
D03*
D87*
X544471Y-273290D02*
D03*
Y-270412D02*
D03*
X580866Y-278931D02*
D03*
Y-276053D02*
D03*
X596220Y-279718D02*
D03*
Y-276840D02*
D03*
X477872Y-298948D02*
D03*
Y-301826D02*
D03*
X189764Y-95927D02*
D03*
Y-93049D02*
D03*
X151751Y2505D02*
D03*
Y5383D02*
D03*
X209449Y4195D02*
D03*
Y1317D02*
D03*
X203839Y-1514D02*
D03*
Y-4392D02*
D03*
X214173Y-1711D02*
D03*
Y-4589D02*
D03*
X204537Y-76439D02*
D03*
Y-73561D02*
D03*
X214173Y-76242D02*
D03*
Y-73364D02*
D03*
X108661Y-47638D02*
D03*
Y-44760D02*
D03*
X281890Y-196715D02*
D03*
Y-193836D02*
D03*
X158661Y-101429D02*
D03*
Y-98551D02*
D03*
D88*
X413911Y-124409D02*
D03*
X417585D02*
D03*
X114829Y-16142D02*
D03*
X111155D02*
D03*
D89*
X64528Y-58729D02*
D03*
Y-53218D02*
D03*
X101969Y-49213D02*
D03*
Y-43701D02*
D03*
X164961Y-98819D02*
D03*
Y-104331D02*
D03*
D113*
X96063Y-48687D02*
D03*
Y-45013D02*
D03*
X153150Y-99738D02*
D03*
Y-103412D02*
D03*
D120*
X558375Y-280755D02*
D03*
X555497D02*
D03*
X478876Y-265748D02*
D03*
X481754D02*
D03*
X495805Y-252362D02*
D03*
X498683D02*
D03*
X509116Y-260136D02*
D03*
X506238D02*
D03*
X496199Y-259842D02*
D03*
X499077D02*
D03*
X564506Y-261119D02*
D03*
X567384D02*
D03*
X574766Y-261122D02*
D03*
X571888D02*
D03*
X340809Y-292913D02*
D03*
X337931D02*
D03*
X321912Y-293701D02*
D03*
X319033D02*
D03*
X327030Y-239764D02*
D03*
X324151D02*
D03*
X376514Y-232972D02*
D03*
X379392D02*
D03*
X611553Y-238583D02*
D03*
X614431D02*
D03*
X612887Y-231102D02*
D03*
X615765D02*
D03*
D124*
X596220Y-283876D02*
D03*
Y-287644D02*
D03*
X580866Y-283482D02*
D03*
Y-287250D02*
D03*
D149*
X118504Y-390698D02*
D03*
D150*
X216142Y-404084D02*
D03*
D155*
X109055Y-30315D02*
D03*
X112205D02*
D03*
X160863Y-121457D02*
D03*
X157713D02*
D03*
X425197Y-105512D02*
D03*
X422047D02*
D03*
X92732Y-13129D02*
D03*
X89583D02*
D03*
X43268Y-48355D02*
D03*
X46417D02*
D03*
X43268Y-43355D02*
D03*
X46417D02*
D03*
X158107Y-137205D02*
D03*
X154957D02*
D03*
X162437Y-136417D02*
D03*
X165587D02*
D03*
X43701Y-148819D02*
D03*
X46850D02*
D03*
X161596Y-117597D02*
D03*
X164746D02*
D03*
X156434Y-132185D02*
D03*
X159583D02*
D03*
X160863Y-125000D02*
D03*
X157713D02*
D03*
X160469Y-128937D02*
D03*
X157319D02*
D03*
D156*
X425938Y-194488D02*
D03*
Y-200000D02*
D03*
X162992Y-42913D02*
D03*
Y-48425D02*
D03*
D157*
X555512Y-340158D02*
D03*
X561024D02*
D03*
X535827Y-338976D02*
D03*
X530315D02*
D03*
X568898Y-319291D02*
D03*
X563386D02*
D03*
X536221Y-300787D02*
D03*
X530709D02*
D03*
X128159Y-65403D02*
D03*
X122648D02*
D03*
X117825Y-47401D02*
D03*
X123337D02*
D03*
X149606Y-80315D02*
D03*
X144095D02*
D03*
X222835Y-138189D02*
D03*
X217323D02*
D03*
X198031Y-111811D02*
D03*
X192520D02*
D03*
D166*
X43925Y-154365D02*
D03*
X46878D02*
D03*
X585335Y-214173D02*
D03*
X582382D02*
D03*
X586909Y-196850D02*
D03*
X583957D02*
D03*
X582382Y-206693D02*
D03*
X585335D02*
D03*
D168*
X590748Y-185827D02*
D03*
X587205D02*
D03*
D172*
X589764Y-178642D02*
D03*
Y-175689D02*
D03*
X589730Y-158745D02*
D03*
Y-161698D02*
D03*
D173*
X581890Y-243602D02*
D03*
Y-240059D02*
D03*
X590158Y-224311D02*
D03*
Y-227854D02*
D03*
X584646Y-228937D02*
D03*
Y-232480D02*
D03*
D177*
X442028Y-154331D02*
D03*
X445374D02*
D03*
X71752Y787D02*
D03*
X68405D02*
D03*
X53248Y-5709D02*
D03*
X56595D02*
D03*
X536434Y-256004D02*
D03*
X533088D02*
D03*
X535257Y-250886D02*
D03*
X531910D02*
D03*
X533249Y-245374D02*
D03*
X529902D02*
D03*
X414725Y-104643D02*
D03*
X418071D02*
D03*
X52854Y394D02*
D03*
X49508D02*
D03*
X64862Y-5709D02*
D03*
X61516D02*
D03*
X92831Y-16929D02*
D03*
X89484D02*
D03*
X23524Y-294882D02*
D03*
X26870D02*
D03*
D188*
X437303Y-144390D02*
D03*
Y-147736D02*
D03*
X441732Y-144390D02*
D03*
Y-147736D02*
D03*
X452854Y-144390D02*
D03*
Y-147736D02*
D03*
X210236Y-40431D02*
D03*
Y-37085D02*
D03*
X215354Y-38291D02*
D03*
Y-34944D02*
D03*
X220866Y-35972D02*
D03*
Y-32626D02*
D03*
X18110Y-296161D02*
D03*
Y-292815D02*
D03*
X8661Y-193012D02*
D03*
Y-189665D02*
D03*
D202*
X281102Y-401427D02*
D03*
X159055D02*
D03*
X155118D02*
D03*
X186614D02*
D03*
X182677D02*
D03*
X241732D02*
D03*
X273228D02*
D03*
X269291D02*
D03*
X257480D02*
D03*
X237795D02*
D03*
X253543D02*
D03*
X222047D02*
D03*
X218110D02*
D03*
X210236D02*
D03*
X206299D02*
D03*
X190551D02*
D03*
X166929D02*
D03*
X170866D02*
D03*
X174803D02*
D03*
X178740D02*
D03*
X229921D02*
D03*
X214173D02*
D03*
X202362D02*
D03*
X249606D02*
D03*
X265354D02*
D03*
X245669D02*
D03*
X277165D02*
D03*
X261417D02*
D03*
X233858D02*
D03*
X225984D02*
D03*
X162992D02*
D03*
D203*
X151181Y-399477D02*
D03*
D206*
X298031Y-115512D02*
D03*
Y-145512D02*
D03*
Y-125512D02*
D03*
Y-135512D02*
D03*
D207*
Y-155512D02*
D03*
D208*
X321260Y-145669D02*
D03*
Y-135669D02*
D03*
Y-125669D02*
D03*
D209*
Y-155669D02*
D03*
D210*
X603110Y-805D02*
D03*
D211*
X574409Y7445D02*
D03*
D212*
Y-9055D02*
D03*
X552709Y7445D02*
D03*
Y-9055D02*
D03*
D213*
X0Y0D02*
D03*
X0Y-378395D02*
D03*
D214*
X608268Y-288779D02*
D03*
Y-271260D02*
D03*
D215*
X620079Y-263583D02*
D03*
Y-296457D02*
D03*
D216*
X138297Y-22096D02*
D03*
Y-69340D02*
D03*
D03*
Y-53592D02*
D03*
X541093Y-320167D02*
D03*
X556841D02*
D03*
X509597D02*
D03*
X556841D02*
D03*
D217*
X194882Y394D02*
D03*
X496457Y-271358D02*
D03*
D218*
X194882Y-78347D02*
D03*
X575197Y-271358D02*
D03*
D219*
X354035Y-38976D02*
D03*
X424803D02*
D03*
X535827Y-112205D02*
D03*
D220*
X390462Y-181769D02*
D03*
X311722D02*
D03*
X390452Y-329890D02*
D03*
X311712D02*
D03*
X261082Y-294702D02*
D03*
Y-215962D02*
D03*
X448573Y-215972D02*
D03*
Y-294712D02*
D03*
D221*
X186221Y-334252D02*
D03*
X198031D02*
D03*
X58268Y-163779D02*
D03*
X209842Y-334252D02*
D03*
X58268Y-323622D02*
D03*
X218110Y-163779D02*
D03*
X58268Y-243701D02*
D03*
X174221Y-334252D02*
D03*
X218110Y-323622D02*
D03*
X162221Y-334252D02*
D03*
X174221D02*
D03*
X198031D02*
D03*
X209842D02*
D03*
X218110Y-163779D02*
D03*
Y-323622D02*
D03*
X58268D02*
D03*
Y-243701D02*
D03*
Y-163779D02*
D03*
X186221Y-334252D02*
D03*
X162221D02*
D03*
D222*
X200876Y-315719D02*
D03*
X75768Y-321622D02*
D03*
X78268Y-159780D02*
D03*
X200610Y-171879D02*
D03*
D223*
X453193Y-334056D02*
D03*
X256593Y-177056D02*
D03*
X256693Y-334056D02*
D03*
X453193Y-177056D02*
D03*
D224*
X-18464Y-326781D02*
D03*
X1535D02*
D03*
Y-306781D02*
D03*
X-18464D02*
D03*
X-18465Y-273630D02*
D03*
X1535D02*
D03*
Y-253630D02*
D03*
X-18465D02*
D03*
Y-220480D02*
D03*
X1535D02*
D03*
Y-200480D02*
D03*
X-18465D02*
D03*
X-18464Y-167332D02*
D03*
X1535D02*
D03*
Y-147332D02*
D03*
X-18464D02*
D03*
D225*
X-8465Y-316781D02*
D03*
X-8465Y-263630D02*
D03*
Y-210480D02*
D03*
X-8465Y-157332D02*
D03*
D226*
X609449Y-98189D02*
D03*
D227*
Y-108189D02*
D03*
Y-118189D02*
D03*
Y-128189D02*
D03*
Y-138189D02*
D03*
Y-148189D02*
D03*
X619449Y-98189D02*
D03*
Y-108189D02*
D03*
Y-118189D02*
D03*
Y-128189D02*
D03*
Y-138189D02*
D03*
Y-148189D02*
D03*
D228*
X181534Y-387757D02*
D03*
X522047Y-270866D02*
D03*
X496620Y-310492D02*
D03*
X61811Y787D02*
D03*
X593307Y-292126D02*
D03*
X245325Y-120837D02*
D03*
X500049Y-256633D02*
D03*
X585039Y-266142D02*
D03*
X560630Y-269291D02*
D03*
X599044Y-275032D02*
D03*
X585039Y-272835D02*
D03*
X581496D02*
D03*
X548425Y-269632D02*
D03*
X541093Y-284626D02*
D03*
X541411Y-269932D02*
D03*
X536489Y-269182D02*
D03*
X554724Y-272441D02*
D03*
X555460Y-284401D02*
D03*
X574406Y-280807D02*
D03*
X567525Y-286203D02*
D03*
X581890Y-290158D02*
D03*
X583815Y-275386D02*
D03*
X614822Y-250158D02*
D03*
X604724Y-274803D02*
D03*
X321260Y-166142D02*
D03*
X150394Y-140157D02*
D03*
X317323Y-114961D02*
D03*
X321260D02*
D03*
X309449Y-211811D02*
D03*
X313386Y-212598D02*
D03*
X124016Y-110236D02*
D03*
X222351Y-98694D02*
D03*
X245276Y-115748D02*
D03*
X211648Y-103695D02*
D03*
X44001Y-137747D02*
D03*
X57422Y-128927D02*
D03*
X89312Y-128140D02*
D03*
X84981D02*
D03*
X80651D02*
D03*
X89312Y-123809D02*
D03*
X84981D02*
D03*
X80651D02*
D03*
X89312Y-119478D02*
D03*
X84981D02*
D03*
X80651D02*
D03*
X58407Y-137589D02*
D03*
X44134Y-115080D02*
D03*
X44621Y-110628D02*
D03*
X58210Y-108061D02*
D03*
X139370Y-118898D02*
D03*
X262724Y-107813D02*
D03*
X253082Y-110236D02*
D03*
X317828Y-161260D02*
D03*
X313878Y-161597D02*
D03*
X286221Y-124803D02*
D03*
X285827Y-137795D02*
D03*
X285384Y-154492D02*
D03*
X284646Y-128347D02*
D03*
X284252Y-144095D02*
D03*
X282058Y-151217D02*
D03*
X281890Y-155905D02*
D03*
X281496Y-124409D02*
D03*
X280709Y-137795D02*
D03*
X276650Y-128810D02*
D03*
X276083Y-152559D02*
D03*
Y-141142D02*
D03*
X255906Y-126378D02*
D03*
Y-131496D02*
D03*
Y-137008D02*
D03*
Y-142126D02*
D03*
X257480Y-150394D02*
D03*
X255512Y-146850D02*
D03*
X140551Y-116535D02*
D03*
X364567Y-326378D02*
D03*
X357575Y-327776D02*
D03*
X357480Y-332677D02*
D03*
X350787Y-329921D02*
D03*
X205906Y-372441D02*
D03*
X211024D02*
D03*
X222835Y-372047D02*
D03*
X217323Y-371654D02*
D03*
X237795D02*
D03*
X242897Y-371864D02*
D03*
X250394Y-375984D02*
D03*
X259449Y-373228D02*
D03*
X268504Y-372047D02*
D03*
X274803Y-372441D02*
D03*
X266929Y-385039D02*
D03*
X243701Y-389370D02*
D03*
X250394Y-384646D02*
D03*
X227953Y-383858D02*
D03*
X233858Y-384646D02*
D03*
X213386D02*
D03*
X513386Y-199213D02*
D03*
X521654Y-198819D02*
D03*
X591339Y-189764D02*
D03*
X153225Y-121747D02*
D03*
X133099Y-136519D02*
D03*
X24500Y-8429D02*
D03*
X603150Y-235946D02*
D03*
X604316Y-246600D02*
D03*
X152756Y-65354D02*
D03*
X157480Y-73228D02*
D03*
X381890Y-183858D02*
D03*
X384646Y-184252D02*
D03*
X359842Y-161024D02*
D03*
X363386Y-160630D02*
D03*
X367717D02*
D03*
X454775Y-308565D02*
D03*
X569685Y-303150D02*
D03*
X608268Y-84252D02*
D03*
X383083Y-161839D02*
D03*
X421313Y-174784D02*
D03*
X396850Y-249016D02*
D03*
X129063Y-136618D02*
D03*
X38613Y-53355D02*
D03*
X172674Y-138386D02*
D03*
X613406Y-89494D02*
D03*
X388189Y-162205D02*
D03*
X419798Y-176745D02*
D03*
X401575Y-249213D02*
D03*
X126307Y-136224D02*
D03*
X38583Y-58355D02*
D03*
X170311Y-139961D02*
D03*
X491732Y-149213D02*
D03*
X500394Y-145669D02*
D03*
X496063Y-145276D02*
D03*
X491732D02*
D03*
X550391Y-243310D02*
D03*
X477165Y-247244D02*
D03*
X539370Y-228740D02*
D03*
X542913D02*
D03*
X561024Y-183465D02*
D03*
Y-186614D02*
D03*
X-4724Y-283071D02*
D03*
X35433Y-129528D02*
D03*
X32283D02*
D03*
X28740D02*
D03*
X35433Y-50787D02*
D03*
X149935Y-124206D02*
D03*
X150233Y-119882D02*
D03*
X429528Y-231496D02*
D03*
X364173Y-280315D02*
D03*
X464961Y-125197D02*
D03*
X50000Y-44094D02*
D03*
X324016Y-42913D02*
D03*
X318898Y-43307D02*
D03*
X324016Y-39764D02*
D03*
X318898D02*
D03*
X324016Y-35827D02*
D03*
X318898D02*
D03*
X505118Y-24016D02*
D03*
X500787Y-24409D02*
D03*
X496457Y-24016D02*
D03*
X505118Y-20079D02*
D03*
X500787D02*
D03*
X496457D02*
D03*
X245669Y-74016D02*
D03*
X246063Y-70079D02*
D03*
X241732Y-74016D02*
D03*
Y-70079D02*
D03*
X326772Y-73622D02*
D03*
X322441D02*
D03*
X317717Y-73228D02*
D03*
X326772Y-69291D02*
D03*
X322441D02*
D03*
X317717D02*
D03*
X427953Y-206299D02*
D03*
X481496Y-197244D02*
D03*
X468504Y-44488D02*
D03*
X463779D02*
D03*
X458661Y-44094D02*
D03*
X468898Y-39764D02*
D03*
X463779Y-39370D02*
D03*
X458661D02*
D03*
X295669Y-45276D02*
D03*
X290945D02*
D03*
X295276Y-40945D02*
D03*
X290945D02*
D03*
X295276Y-35433D02*
D03*
X290945D02*
D03*
X118504Y-40945D02*
D03*
X85039Y-77559D02*
D03*
X383465Y-234252D02*
D03*
X389764D02*
D03*
X386614Y-237402D02*
D03*
Y-231102D02*
D03*
X611811Y-221260D02*
D03*
X426772Y-179528D02*
D03*
X418898Y-245276D02*
D03*
X602105Y-99109D02*
D03*
X597244Y-108661D02*
D03*
X592913Y-116535D02*
D03*
X594488Y-132677D02*
D03*
X43701Y-34646D02*
D03*
X51287Y-126878D02*
D03*
X13386D02*
D03*
X29543Y-345214D02*
D03*
X240158Y-278740D02*
D03*
X26378Y-20472D02*
D03*
X24409Y-16535D02*
D03*
X26378Y-10630D02*
D03*
X35433Y15354D02*
D03*
X36220Y8268D02*
D03*
X35827Y1575D02*
D03*
X19685Y-2362D02*
D03*
X20079Y3937D02*
D03*
Y10630D02*
D03*
Y17323D02*
D03*
X298819Y-269685D02*
D03*
X391339Y-277953D02*
D03*
X299606Y-185433D02*
D03*
X231102Y-239764D02*
D03*
X230709Y-242913D02*
D03*
X399213Y-193307D02*
D03*
X204331Y-101575D02*
D03*
X432283Y-254724D02*
D03*
X496063Y-244094D02*
D03*
X173228Y-117323D02*
D03*
X261024Y-200394D02*
D03*
X381890Y-254331D02*
D03*
X318989Y-253024D02*
D03*
X337402Y-260630D02*
D03*
X429134Y-246850D02*
D03*
X483831Y-241339D02*
D03*
X488189Y-216535D02*
D03*
X500971Y-219896D02*
D03*
X470472Y-246457D02*
D03*
X476968Y-76378D02*
D03*
X462992D02*
D03*
X289370Y-205906D02*
D03*
X153150Y-113386D02*
D03*
X226378Y-32677D02*
D03*
X100394Y-30315D02*
D03*
X383071Y-276772D02*
D03*
X402756Y-281102D02*
D03*
X616929Y-225984D02*
D03*
X611614Y-186107D02*
D03*
X586221Y-178740D02*
D03*
X591339Y-144488D02*
D03*
X586614Y-158661D02*
D03*
X582165Y-163898D02*
D03*
X581890Y-174016D02*
D03*
X579134Y-214006D02*
D03*
X581890Y-235925D02*
D03*
X584646Y-225197D02*
D03*
X590188Y-221161D02*
D03*
X608661Y-220472D02*
D03*
X589370Y-212992D02*
D03*
X588922Y-206462D02*
D03*
X583858Y-192913D02*
D03*
X589370Y-201575D02*
D03*
X27559Y-337402D02*
D03*
X341339Y-277953D02*
D03*
X407874Y-216535D02*
D03*
X408760Y-238189D02*
D03*
X462473Y-277635D02*
D03*
X321850Y-283465D02*
D03*
X461417Y-305118D02*
D03*
X598397Y-88288D02*
D03*
X603543Y-87795D02*
D03*
X135433Y-79134D02*
D03*
X424409Y-205512D02*
D03*
X428346Y-187795D02*
D03*
X140070Y-132385D02*
D03*
X140116Y-124048D02*
D03*
X141339Y394D02*
D03*
X180610Y-87795D02*
D03*
X198524D02*
D03*
X197244Y-102756D02*
D03*
X181004Y-101181D02*
D03*
X177559Y-87795D02*
D03*
X197638Y-97638D02*
D03*
X182283Y-97244D02*
D03*
X182677Y-94488D02*
D03*
X189764Y-88189D02*
D03*
Y-100787D02*
D03*
X196850Y-94488D02*
D03*
X161417Y-25984D02*
D03*
X169291Y13386D02*
D03*
Y9646D02*
D03*
X159843D02*
D03*
X151181Y14173D02*
D03*
X142520Y13189D02*
D03*
X144685Y-11811D02*
D03*
X162598Y-9449D02*
D03*
X153543Y-10433D02*
D03*
X162598Y-13189D02*
D03*
Y-1575D02*
D03*
X151181Y18110D02*
D03*
X137598Y-6299D02*
D03*
X134055D02*
D03*
X149803Y-9238D02*
D03*
X150000Y-787D02*
D03*
X151782Y10443D02*
D03*
X473303Y-276476D02*
D03*
X479331Y-294626D02*
D03*
X487402Y-256988D02*
D03*
X485827Y-279429D02*
D03*
X476772Y-254035D02*
D03*
X473622Y-259055D02*
D03*
X476378Y-273622D02*
D03*
X486221Y-265748D02*
D03*
X474409D02*
D03*
X480315Y-259744D02*
D03*
Y-271752D02*
D03*
X548819Y-300787D02*
D03*
X489567Y-310236D02*
D03*
X492323Y-303543D02*
D03*
X495866D02*
D03*
X483465Y-291535D02*
D03*
X476772Y-291929D02*
D03*
X466142Y-294685D02*
D03*
Y-298228D02*
D03*
X461417Y-312099D02*
D03*
X473819Y-315354D02*
D03*
X484842Y-317717D02*
D03*
X493110Y-310236D02*
D03*
X461024Y-302756D02*
D03*
X498425Y-307087D02*
D03*
X478346Y-305118D02*
D03*
X477362Y-313767D02*
D03*
X596865Y-266396D02*
D03*
X594765D02*
D03*
X624938Y-196373D02*
D03*
X624926Y-201353D02*
D03*
X624938Y-206373D02*
D03*
X624918Y-211353D02*
D03*
X625079Y-173898D02*
D03*
X624685Y-163898D02*
D03*
X551968Y-297638D02*
D03*
X127165Y-12598D02*
D03*
X118110Y-36220D02*
D03*
X117717Y-47293D02*
D03*
X121653Y-31496D02*
D03*
X404493Y-224149D02*
D03*
X404626Y-219685D02*
D03*
X578332Y-261235D02*
D03*
X507874Y-255906D02*
D03*
X534814Y-297190D02*
D03*
X528960Y-296841D02*
D03*
X495276Y-298130D02*
D03*
X503346Y-297967D02*
D03*
X507480Y-298130D02*
D03*
X501181D02*
D03*
X516929D02*
D03*
X522835Y-297736D02*
D03*
X540945Y-297342D02*
D03*
X546457D02*
D03*
X562205Y-297736D02*
D03*
X568110D02*
D03*
X570472D02*
D03*
X576378D02*
D03*
X571260Y-256791D02*
D03*
X568898D02*
D03*
X550000Y-255610D02*
D03*
X540945Y-256004D02*
D03*
X538976Y-250886D02*
D03*
X536614Y-245374D02*
D03*
X518110Y-255217D02*
D03*
X522047Y-249705D02*
D03*
X524016Y-243799D02*
D03*
X502362Y-257185D02*
D03*
X504331D02*
D03*
X513386Y-254429D02*
D03*
X508268Y-251673D02*
D03*
X564173Y-255906D02*
D03*
X494882Y-262303D02*
D03*
X495669Y-255512D02*
D03*
X209449Y7087D02*
D03*
X203937Y1969D02*
D03*
X214173Y1181D02*
D03*
Y-79134D02*
D03*
X205118Y-79380D02*
D03*
X214567Y-11417D02*
D03*
X211811Y-16535D02*
D03*
X209055Y-7480D02*
D03*
Y-5512D02*
D03*
X209449Y-3543D02*
D03*
X216535Y-25197D02*
D03*
X211024Y-21260D02*
D03*
X220866Y-39764D02*
D03*
X215354Y-42126D02*
D03*
X210236Y-44094D02*
D03*
X210630Y-53150D02*
D03*
X209541Y-58689D02*
D03*
X209449Y-72047D02*
D03*
Y-74410D02*
D03*
X168504Y-79528D02*
D03*
Y-73622D02*
D03*
Y-71260D02*
D03*
Y-65354D02*
D03*
X168898Y-49606D02*
D03*
Y-44094D02*
D03*
X168504Y-37795D02*
D03*
Y-31890D02*
D03*
Y-25984D02*
D03*
X168110Y-20079D02*
D03*
Y-4331D02*
D03*
Y-10630D02*
D03*
X168273Y-6496D02*
D03*
X168110Y1575D02*
D03*
X101181Y-38583D02*
D03*
X144095Y-80315D02*
D03*
X149606D02*
D03*
X117323Y-65354D02*
D03*
X121467Y-74575D02*
D03*
X-18601Y-349409D02*
D03*
X87795Y-99606D02*
D03*
X540551Y-340945D02*
D03*
X535827Y-345276D02*
D03*
X555512Y-340158D02*
D03*
X544882Y-336221D02*
D03*
X552756Y-335827D02*
D03*
X561024Y-340158D02*
D03*
X568898Y-319009D02*
D03*
X570079Y-309921D02*
D03*
X552756Y-305118D02*
D03*
X544882D02*
D03*
X536221Y-300787D02*
D03*
X530709D02*
D03*
X530315Y-338976D02*
D03*
X513406Y-302902D02*
D03*
X521654Y-336221D02*
D03*
X513386D02*
D03*
X505410Y-336036D02*
D03*
X505512Y-303150D02*
D03*
X455118Y-92520D02*
D03*
X460236Y-87795D02*
D03*
Y-92520D02*
D03*
X454724Y-87795D02*
D03*
X624409Y-31496D02*
D03*
X620079Y-31890D02*
D03*
X615748Y-32283D02*
D03*
X611417Y-33071D02*
D03*
X620866Y-35827D02*
D03*
X611811Y-38189D02*
D03*
X601181Y-23622D02*
D03*
X597244D02*
D03*
Y-29921D02*
D03*
X601181Y-26772D02*
D03*
Y-29921D02*
D03*
X597244Y-26772D02*
D03*
X542913Y-72835D02*
D03*
Y-69291D02*
D03*
Y-65748D02*
D03*
Y-61811D02*
D03*
Y-58268D02*
D03*
X595276Y-79921D02*
D03*
X608405Y-70079D02*
D03*
X618110Y-62205D02*
D03*
X616142Y-47638D02*
D03*
X618898Y-50787D02*
D03*
X613386D02*
D03*
X609547Y-51181D02*
D03*
X606693Y-50787D02*
D03*
X601575Y-53543D02*
D03*
X599213Y-50000D02*
D03*
X544095Y-42126D02*
D03*
X539764D02*
D03*
X534646Y-51968D02*
D03*
X534252Y-48425D02*
D03*
X534646Y-45276D02*
D03*
Y-42126D02*
D03*
X238189Y-107087D02*
D03*
X233071D02*
D03*
X223228Y-107480D02*
D03*
X228346D02*
D03*
X238189Y-138976D02*
D03*
X233209Y-139232D02*
D03*
X228209Y-138721D02*
D03*
X217405Y-138189D02*
D03*
X223209Y-137815D02*
D03*
X214173Y-107087D02*
D03*
X192126Y-111811D02*
D03*
X199193Y-105925D02*
D03*
X204193Y-138257D02*
D03*
X199193Y-138680D02*
D03*
X130245Y-120870D02*
D03*
X133099Y-119984D02*
D03*
X148425Y-104336D02*
D03*
X153150Y-103412D02*
D03*
Y-99691D02*
D03*
X158268Y-107480D02*
D03*
X168110Y-103937D02*
D03*
Y-100132D02*
D03*
X161417Y-95276D02*
D03*
Y-107480D02*
D03*
X178185Y-136811D02*
D03*
Y-133661D02*
D03*
X150627Y-130512D02*
D03*
X150233Y-127362D02*
D03*
X152904Y-124213D02*
D03*
X152398Y-117717D02*
D03*
X156926Y-111614D02*
D03*
X164843Y-114040D02*
D03*
X160075Y-112402D02*
D03*
X168343Y-110827D02*
D03*
X186847Y-135236D02*
D03*
X188028Y-113583D02*
D03*
X189209Y-131339D02*
D03*
Y-117480D02*
D03*
X173461Y-127362D02*
D03*
X165587Y-139961D02*
D03*
X151808Y-137205D02*
D03*
X162241Y-140004D02*
D03*
X106693Y15354D02*
D03*
X107087Y9449D02*
D03*
X111024D02*
D03*
Y15354D02*
D03*
X105512Y-79921D02*
D03*
X109843D02*
D03*
Y-74410D02*
D03*
X105512D02*
D03*
X99606Y-63779D02*
D03*
X107874D02*
D03*
Y-59842D02*
D03*
X99606D02*
D03*
X74616Y-61723D02*
D03*
X56693Y1060D02*
D03*
X39764Y-29528D02*
D03*
Y-25984D02*
D03*
X35731Y-9843D02*
D03*
Y-18898D02*
D03*
X47441Y-27362D02*
D03*
Y-21260D02*
D03*
Y-5709D02*
D03*
Y-11811D02*
D03*
X75394Y-5709D02*
D03*
Y-11811D02*
D03*
X66142D02*
D03*
X61417D02*
D03*
X56693D02*
D03*
Y-16535D02*
D03*
X61417D02*
D03*
X66142D02*
D03*
Y-21260D02*
D03*
X61417D02*
D03*
X52362Y-35531D02*
D03*
X61417Y-35741D02*
D03*
X37402Y-43355D02*
D03*
X38382Y-48355D02*
D03*
X66102Y-64085D02*
D03*
X72795Y-53355D02*
D03*
X86614Y-56299D02*
D03*
X91339Y-35039D02*
D03*
X86614Y-39370D02*
D03*
X88583Y-53937D02*
D03*
X85039D02*
D03*
X88583Y-50787D02*
D03*
X85039D02*
D03*
X88583Y-46457D02*
D03*
X85039Y-46850D02*
D03*
X84252Y-9055D02*
D03*
Y-5906D02*
D03*
Y-2362D02*
D03*
X88257Y-2500D02*
D03*
X93608Y-3379D02*
D03*
X90158Y-7480D02*
D03*
X107832Y-10197D02*
D03*
X97408D02*
D03*
X106693Y-27559D02*
D03*
X105282Y-19291D02*
D03*
X85827Y-16929D02*
D03*
X85853Y-13780D02*
D03*
X78740Y18110D02*
D03*
Y15354D02*
D03*
Y9843D02*
D03*
Y6693D02*
D03*
Y3543D02*
D03*
X110589Y1589D02*
D03*
X108268Y394D02*
D03*
X112598D02*
D03*
X116929Y-21654D02*
D03*
X118898Y-16929D02*
D03*
X366043Y-153937D02*
D03*
X373228Y-162598D02*
D03*
X378346Y-161811D02*
D03*
X388713Y-128731D02*
D03*
X383083Y-128504D02*
D03*
X336221Y-122047D02*
D03*
X333465D02*
D03*
X330315Y-121653D02*
D03*
X335827Y-164173D02*
D03*
X333071D02*
D03*
X329919Y-164008D02*
D03*
X329656Y-142480D02*
D03*
X329722Y-145827D02*
D03*
X347638Y-119882D02*
D03*
X347244Y-113189D02*
D03*
X355035Y-105876D02*
D03*
X390654Y-104510D02*
D03*
X383465Y-103543D02*
D03*
X369685Y-123622D02*
D03*
Y-120866D02*
D03*
Y-118110D02*
D03*
X366929Y-123622D02*
D03*
Y-120866D02*
D03*
X363779Y-123622D02*
D03*
X366929Y-118110D02*
D03*
X363779Y-120866D02*
D03*
Y-118110D02*
D03*
X448425Y-165354D02*
D03*
X451968D02*
D03*
X455512D02*
D03*
X458661D02*
D03*
X442815Y-161747D02*
D03*
Y-165847D02*
D03*
X439561D02*
D03*
X425984Y-109843D02*
D03*
X425630Y-112894D02*
D03*
X416535Y-120768D02*
D03*
X423622Y-115354D02*
D03*
X436811Y-153543D02*
D03*
X418110D02*
D03*
X422835D02*
D03*
X427559D02*
D03*
Y-148819D02*
D03*
X418110D02*
D03*
X422835D02*
D03*
Y-144095D02*
D03*
X418110D02*
D03*
X422835Y-131791D02*
D03*
X427843Y-166966D02*
D03*
X422835Y-166284D02*
D03*
X406693Y-125984D02*
D03*
X408268Y-124409D02*
D03*
Y-122047D02*
D03*
X400984Y-127102D02*
D03*
X415748Y-129609D02*
D03*
X418898Y-129753D02*
D03*
X445276Y-103543D02*
D03*
X444488Y-106299D02*
D03*
X440945Y-105905D02*
D03*
X436221Y-106299D02*
D03*
X434347Y-103743D02*
D03*
X434646Y-100787D02*
D03*
X431496Y-100000D02*
D03*
X422047Y-101969D02*
D03*
X418898Y-100000D02*
D03*
X445669Y-128347D02*
D03*
X449606D02*
D03*
Y-124803D02*
D03*
Y-121653D02*
D03*
X275590Y-199606D02*
D03*
X289370Y-200394D02*
D03*
X274803Y-188583D02*
D03*
X291831Y-197012D02*
D03*
X295669Y-191339D02*
D03*
X292815Y-187106D02*
D03*
X275590Y-184252D02*
D03*
X281890Y-188583D02*
D03*
Y-200771D02*
D03*
X288583Y-195276D02*
D03*
X275503D02*
D03*
X596063Y-239895D02*
D03*
Y-241995D02*
D03*
X321654Y-232677D02*
D03*
X336614Y-286221D02*
D03*
X315945Y-287795D02*
D03*
X315333Y-299430D02*
D03*
X336811Y-299399D02*
D03*
X313386Y-283465D02*
D03*
X308268Y-300000D02*
D03*
X324184Y-302194D02*
D03*
X356693Y-288583D02*
D03*
X355741Y-296063D02*
D03*
X314961Y-293701D02*
D03*
X320472Y-299569D02*
D03*
X325776Y-293701D02*
D03*
X320472Y-287865D02*
D03*
X345161Y-292913D02*
D03*
X333465D02*
D03*
X339370Y-286162D02*
D03*
Y-298819D02*
D03*
X329134Y-228740D02*
D03*
X341274Y-242913D02*
D03*
X340786Y-235827D02*
D03*
X312322Y-236221D02*
D03*
X309782Y-243307D02*
D03*
X334842Y-247244D02*
D03*
X319685Y-245276D02*
D03*
X333714Y-239764D02*
D03*
X325590Y-246324D02*
D03*
Y-232344D02*
D03*
X317009Y-239764D02*
D03*
X390896Y-249065D02*
D03*
X386615Y-249113D02*
D03*
X400000Y-219291D02*
D03*
X398472Y-235531D02*
D03*
X378937Y-249803D02*
D03*
X367654Y-236614D02*
D03*
X373093Y-232972D02*
D03*
X375197Y-221260D02*
D03*
X382776Y-221555D02*
D03*
X368232Y-217717D02*
D03*
X390158D02*
D03*
X415623Y-358391D02*
D03*
X414772Y-353273D02*
D03*
X449150Y-355832D02*
D03*
X460678Y-359179D02*
D03*
X460900Y-354061D02*
D03*
X493234Y-356620D02*
D03*
X533931Y-356296D02*
D03*
X499525Y-358855D02*
D03*
X499302Y-353737D02*
D03*
X579072Y-356690D02*
D03*
X561330Y-356099D02*
D03*
X543698Y-358659D02*
D03*
X543718Y-353540D02*
D03*
X626987Y-228346D02*
D03*
X605512Y-261024D02*
D03*
Y-256693D02*
D03*
X622835Y-244094D02*
D03*
Y-235433D02*
D03*
X618504Y-252362D02*
D03*
X622101Y-250000D02*
D03*
X622803Y-241006D02*
D03*
X605317Y-252756D02*
D03*
X610236Y-300000D02*
D03*
X619148Y-302756D02*
D03*
X622221Y-313481D02*
D03*
X622753Y-353307D02*
D03*
X622677Y-333307D02*
D03*
X623228Y-343307D02*
D03*
X598583Y-353307D02*
D03*
X598819Y-343307D02*
D03*
X598959Y-333307D02*
D03*
X598898Y-313307D02*
D03*
X393701Y-168898D02*
D03*
X378594Y-166966D02*
D03*
X348031Y-165748D02*
D03*
X342808Y-166966D02*
D03*
X337795Y-181102D02*
D03*
X334252Y-180315D02*
D03*
X310236Y-165748D02*
D03*
X309055Y-195669D02*
D03*
X314675Y-198819D02*
D03*
X319291Y-196850D02*
D03*
X373730Y-202888D02*
D03*
X375698Y-197700D02*
D03*
X383572Y-206205D02*
D03*
X385541Y-202460D02*
D03*
X155427Y-33907D02*
D03*
X155328Y-26033D02*
D03*
X122539D02*
D03*
X142126Y-348031D02*
D03*
X141587Y-352161D02*
D03*
X22047Y-335433D02*
D03*
X2097Y-349213D02*
D03*
X27067Y-282677D02*
D03*
X5584Y-238905D02*
D03*
X35120Y-228937D02*
D03*
X10630Y-197638D02*
D03*
X22441Y-167323D02*
D03*
X19685D02*
D03*
X16929D02*
D03*
X23228Y-147244D02*
D03*
X20079D02*
D03*
X17323D02*
D03*
X27165Y-179134D02*
D03*
X26772Y-348819D02*
D03*
X-1181Y-352831D02*
D03*
X4331Y-344488D02*
D03*
X12598Y-349213D02*
D03*
X35039Y-289961D02*
D03*
Y-285827D02*
D03*
X27067Y-298727D02*
D03*
X10630Y-292126D02*
D03*
X14173Y-294320D02*
D03*
X288Y-234968D02*
D03*
X10007D02*
D03*
X19685Y-239370D02*
D03*
X14665Y-237402D02*
D03*
X36220Y-235039D02*
D03*
X36614Y-232677D02*
D03*
X35039Y-237402D02*
D03*
X30709Y-190411D02*
D03*
X33071Y-185755D02*
D03*
X35827D02*
D03*
X13780Y-190551D02*
D03*
X9843Y-185755D02*
D03*
X19682Y-192520D02*
D03*
X198392Y-366842D02*
D03*
X196701Y-370523D02*
D03*
X394193Y-197670D02*
D03*
X380363Y-196740D02*
D03*
X230165Y-235119D02*
D03*
X230406Y-251861D02*
D03*
X230251Y-232266D02*
D03*
D229*
X127392Y-94557D02*
D03*
X365581Y7806D02*
D03*
Y-94557D02*
D03*
X127392Y7806D02*
D03*
X479695Y-331073D02*
D03*
X582058Y-92884D02*
D03*
X479695D02*
D03*
X582058Y-331073D02*
D03*
D259*
X412205Y-129528D02*
D03*
X408268D02*
D03*
D260*
X431943Y-132677D02*
D03*
X427900D02*
D03*
D262*
X56824Y-31594D02*
D03*
Y-35531D02*
D03*
D266*
X561024Y-330315D02*
D03*
X553150D02*
D03*
X529282Y-328837D02*
D03*
X537156D02*
D03*
X562205Y-309842D02*
D03*
X570079D02*
D03*
X529282Y-312272D02*
D03*
X537156D02*
D03*
X125984Y-36220D02*
D03*
X118110D02*
D03*
X121467Y-74575D02*
D03*
X129341D02*
D03*
X144096Y-71072D02*
D03*
X151970D02*
D03*
D267*
X148632Y-49655D02*
D03*
Y-41781D02*
D03*
D268*
X612781Y-302756D02*
D03*
X615762D02*
D03*
X152904Y-124213D02*
D03*
X149924D02*
D03*
D271*
X388713Y-135039D02*
D03*
X383201D02*
D03*
X613779Y-64961D02*
D03*
X608268D02*
D03*
D276*
X564889Y-280519D02*
D03*
Y-282487D02*
D03*
Y-278550D02*
D03*
Y-276582D02*
D03*
X570676D02*
D03*
Y-278550D02*
D03*
Y-280519D02*
D03*
Y-282487D02*
D03*
X536772Y-273701D02*
D03*
Y-271732D02*
D03*
Y-275669D02*
D03*
Y-277638D02*
D03*
X530984D02*
D03*
Y-275669D02*
D03*
Y-273701D02*
D03*
Y-271732D02*
D03*
D277*
X532266Y-282481D02*
D03*
X536203D02*
D03*
X568963Y-272841D02*
D03*
X565026D02*
D03*
X558727Y-275597D02*
D03*
X554790D02*
D03*
D278*
X542126Y-277953D02*
D03*
Y-281890D02*
D03*
D279*
X111024Y-21752D02*
D03*
Y-25492D02*
D03*
D280*
X287835Y-273622D02*
D03*
X293268D02*
D03*
D281*
X400984Y-129921D02*
D03*
X403937D02*
D03*
D282*
X423917Y-137992D02*
D03*
X427658D02*
D03*
X56595Y-27362D02*
D03*
X60335D02*
D03*
D283*
X378083Y-153937D02*
D03*
Y-157087D02*
D03*
X373083Y-153937D02*
D03*
Y-157087D02*
D03*
X603357Y-83008D02*
D03*
Y-79858D02*
D03*
X598425Y-83071D02*
D03*
Y-79921D02*
D03*
X158008Y-118602D02*
D03*
Y-115453D02*
D03*
X164012Y-128150D02*
D03*
Y-131299D02*
D03*
D284*
X432237Y-199705D02*
D03*
Y-204232D02*
D03*
D285*
X26083Y16339D02*
D03*
X31398D02*
D03*
X26083Y9449D02*
D03*
X31398D02*
D03*
X26083Y2559D02*
D03*
X31398D02*
D03*
X26083Y-4331D02*
D03*
X31398D02*
D03*
X199114Y-130709D02*
D03*
X204035D02*
D03*
D286*
X604252Y-242991D02*
D03*
X601181D02*
D03*
X604252Y-239054D02*
D03*
X601181D02*
D03*
D287*
X172939Y-124276D02*
D03*
Y-120812D02*
D03*
X59016Y-54241D02*
D03*
Y-57706D02*
D03*
X168441Y-115295D02*
D03*
Y-118760D02*
D03*
X273441Y-382293D02*
D03*
Y-378907D02*
D03*
X206441D02*
D03*
Y-382293D02*
D03*
X210441D02*
D03*
Y-378907D02*
D03*
X218341D02*
D03*
Y-382293D02*
D03*
X222641D02*
D03*
Y-378907D02*
D03*
X237941Y-382293D02*
D03*
Y-378907D02*
D03*
X241941Y-382293D02*
D03*
Y-378907D02*
D03*
X253441Y-382293D02*
D03*
Y-378907D02*
D03*
X256941D02*
D03*
Y-382293D02*
D03*
X269441D02*
D03*
Y-378907D02*
D03*
D288*
X609291Y-59842D02*
D03*
X612756D02*
D03*
X384532Y-141339D02*
D03*
X387996D02*
D03*
D289*
X228150Y-132677D02*
D03*
X223031D02*
D03*
X238386Y-131890D02*
D03*
X233268D02*
D03*
M02*
